(kicad_pcb
	(version 20260206)
	(generator "pcbnew")
	(generator_version "10.0")
	(general
		(thickness 1.6)
		(legacy_teardrops no)
	)
	(paper "A4")
	(title_block
		(title "Bryce Canyon_F.DPB_16315-1-OCP.brd")
		(comment 1 "Bryce Canyon / footprints 1463-1469 of 2223")
	)
	(layers
		(0 "F.Cu" signal "TOP")
		(4 "In1.Cu" signal "L2GND")
		(6 "In2.Cu" signal "L3")
		(8 "In3.Cu" signal "L4GND")
		(10 "In4.Cu" signal "L5")
		(12 "In5.Cu" signal "L6VCC")
		(14 "In6.Cu" signal "L7VCC")
		(16 "In7.Cu" signal "L8")
		(18 "In8.Cu" signal "L9GND")
		(20 "In9.Cu" signal "L10")
		(22 "In10.Cu" signal "L11GND")
		(2 "B.Cu" signal "BOTTOM")
		(9 "F.Adhes" user "F.Adhesive")
		(11 "B.Adhes" user "B.Adhesive")
		(13 "F.Paste" user "Package Geometry/Pastemask Top")
		(15 "B.Paste" user "Package Geometry/Pastemask Bottom")
		(5 "F.SilkS" user "Ref Des/Silkscreen Top")
		(7 "B.SilkS" user "Ref Des/Silkscreen Bottom")
		(1 "F.Mask" user "Board Geometry/Soldermask Top")
		(3 "B.Mask" user "Board Geometry/Soldermask Bottom")
		(17 "Dwgs.User" user "User.Drawings")
		(19 "Cmts.User" user "User.Comments")
		(21 "Eco1.User" user "User.Eco1")
		(23 "Eco2.User" user "User.Eco2")
		(25 "Edge.Cuts" user "Board Geometry/Outline")
		(27 "Margin" user)
		(31 "F.CrtYd" user "Package Geometry/Place Bound Top")
		(29 "B.CrtYd" user "Package Geometry/Place Bound Bottom")
		(35 "F.Fab" user "Ref Des/Assembly Top")
		(33 "B.Fab" user "Ref Des/Assembly Bottom")
	)
	(footprint ""
		(layer "F.Cu")
		(at 363.020102 -291.127942 -90)
		(property "Reference" "R290"
			(at 0 0 270)
			(layer "F.SilkS")
			(hide yes)
			(effects
				(font
					(size 1.27 1.27)
				)
			)
		)
		(property "Value" "2R6F-GP"
			(at -0.0508 -4.8514 270)
			(unlocked yes)
			(layer "F.Fab")
			(hide yes)
			(effects
				(font
					(size 1.016 1.016)
					(thickness 0.1524)
				)
			)
		)
		(property "Device Type" "R1206H26"
			(at 0 -6.3754 270)
			(unlocked yes)
			(layer "F.Fab")
			(hide yes)
			(effects
				(font
					(size 1.016 1.016)
					(thickness 0.1524)
				)
			)
		)
		(duplicate_pad_numbers_are_jumpers no)
		(fp_line
			(start -1.016 2.2352)
			(end -1.016 -2.2352)
			(stroke
				(width 0.1524)
				(type default)
			)
			(layer "F.SilkS")
		)
		(fp_line
			(start 1.016 2.2352)
			(end -1.016 2.2352)
			(stroke
				(width 0.1524)
				(type default)
			)
			(layer "F.SilkS")
		)
		(fp_line
			(start -1.016 -2.2352)
			(end 1.016 -2.2352)
			(stroke
				(width 0.1524)
				(type default)
			)
			(layer "F.SilkS")
		)
		(fp_line
			(start 1.016 -2.2352)
			(end 1.016 2.2352)
			(stroke
				(width 0.1524)
				(type default)
			)
			(layer "F.SilkS")
		)
		(fp_rect
			(start -1.0922 2.3114)
			(end 1.0922 -2.3114)
			(stroke
				(width 0)
				(type default)
			)
			(fill no)
			(layer "F.CrtYd")
		)
		(fp_poly
			(pts
				(xy -1.0922 -2.3114) (xy 1.0922 -2.3114) (xy 1.0922 2.3114) (xy -1.0922 2.3114)
			)
			(stroke
				(width 0)
				(type default)
			)
			(fill no)
			(layer "F.Fab")
		)
		(pad "1" smd rect
			(at 0 -1.397 270)
			(size 1.651 1.27)
			(layers "F.Cu" "F.Mask" "F.Paste")
			(net "P5V_HDD7")
		)
		(pad "2" smd rect
			(at 0 1.397 270)
			(size 1.651 1.27)
			(layers "F.Cu" "F.Mask" "F.Paste")
			(net "5V_PRE_7")
		)
	)
	(footprint ""
		(layer "F.Cu")
		(at 400.03095 -160.735518 180)
		(property "Reference" "R604"
			(at 0 0 180)
			(layer "F.SilkS")
			(hide yes)
			(effects
				(font
					(size 1.27 1.27)
				)
			)
		)
		(property "Value" "4K7R2J-2-GP"
			(at 0.064008 -3.993896 180)
			(unlocked yes)
			(layer "F.Fab")
			(hide yes)
			(effects
				(font
					(size 1.016 1.016)
					(thickness 0.1524)
				)
			)
		)
		(property "Device Type" "R402H16"
			(at 0.064008 -5.517896 180)
			(unlocked yes)
			(layer "F.Fab")
			(hide yes)
			(effects
				(font
					(size 1.016 1.016)
					(thickness 0.1524)
				)
			)
		)
		(duplicate_pad_numbers_are_jumpers no)
		(fp_line
			(start 0.508 -0.9398)
			(end -0.508 -0.9398)
			(stroke
				(width 0.1524)
				(type default)
			)
			(layer "F.SilkS")
		)
		(fp_line
			(start -0.508 -0.9398)
			(end -0.508 0.9398)
			(stroke
				(width 0.1524)
				(type default)
			)
			(layer "F.SilkS")
		)
		(fp_rect
			(start -0.508 0.9398)
			(end 0.508 -0.9398)
			(stroke
				(width 0)
				(type default)
			)
			(fill no)
			(layer "F.CrtYd")
		)
		(fp_rect
			(start -0.508 0.9398)
			(end 0.508 -0.9398)
			(stroke
				(width 0)
				(type default)
			)
			(fill no)
			(layer "F.Fab")
		)
		(pad "1" smd custom
			(at 0 -0.4445 180)
			(size 0.1397 0.1397)
			(layers "F.Cu" "F.Mask" "F.Paste")
			(net "P12V_A")
			(options
				(clearance outline)
				(anchor circle)
			)
			(primitives
				(gr_poly
					(pts
						(arc
							(start -0.1778 -0.2794)
							(mid -0.249642 -0.249642)
							(end -0.2794 -0.1778)
						)
						(arc
							(start -0.2794 0.1778)
							(mid -0.249642 0.249642)
							(end -0.1778 0.2794)
						)
						(arc
							(start 0.1778 0.2794)
							(mid 0.249642 0.249642)
							(end 0.2794 0.1778)
						)
						(arc
							(start 0.2794 -0.1778)
							(mid 0.249642 -0.249642)
							(end 0.1778 -0.2794)
						)
					)
					(width 0)
					(fill yes)
				)
			)
		)
		(pad "2" smd custom
			(at 0 0.4445 180)
			(size 0.1397 0.1397)
			(layers "F.Cu" "F.Mask" "F.Paste")
			(net "SW_HDD_R20")
			(options
				(clearance outline)
				(anchor circle)
			)
			(primitives
				(gr_poly
					(pts
						(arc
							(start -0.1778 -0.2794)
							(mid -0.249642 -0.249642)
							(end -0.2794 -0.1778)
						)
						(arc
							(start -0.2794 0.1778)
							(mid -0.249642 0.249642)
							(end -0.1778 0.2794)
						)
						(arc
							(start 0.1778 0.2794)
							(mid 0.249642 0.249642)
							(end 0.2794 0.1778)
						)
						(arc
							(start 0.2794 -0.1778)
							(mid 0.249642 -0.249642)
							(end 0.1778 -0.2794)
						)
					)
					(width 0)
					(fill yes)
				)
			)
		)
	)
	(footprint ""
		(layer "F.Cu")
		(at 381.224028 -136.9314 90)
		(property "Reference" "C95"
			(at 0 0 90)
			(layer "F.SilkS")
			(hide yes)
			(effects
				(font
					(size 1.27 1.27)
				)
			)
		)
		(property "Value" "SC1U16V3KX-5GP"
			(at 0 -2.8194 90)
			(unlocked yes)
			(layer "F.Fab")
			(hide yes)
			(effects
				(font
					(size 1.016 1.016)
					(thickness 0.1524)
				)
			)
		)
		(property "Device Type" "C603H36"
			(at 0 -4.3434 90)
			(unlocked yes)
			(layer "F.Fab")
			(hide yes)
			(effects
				(font
					(size 1.016 1.016)
					(thickness 0.1524)
				)
			)
		)
		(duplicate_pad_numbers_are_jumpers no)
		(fp_line
			(start 0.508 0)
			(end -0.508 0)
			(stroke
				(width 0.2032)
				(type default)
			)
			(layer "F.SilkS")
		)
		(fp_rect
			(start -0.5842 1.3335)
			(end 0.5842 -1.3335)
			(stroke
				(width 0)
				(type default)
			)
			(fill no)
			(layer "F.CrtYd")
		)
		(fp_rect
			(start -0.5842 1.3335)
			(end 0.5842 -1.3335)
			(stroke
				(width 0)
				(type default)
			)
			(fill no)
			(layer "F.Fab")
		)
		(pad "1" smd custom
			(at 0 -0.762 90)
			(size 0.2159 0.2159)
			(layers "F.Cu" "F.Mask" "F.Paste")
			(net "P3V3_B_BIAS")
			(options
				(clearance outline)
				(anchor circle)
			)
			(primitives
				(gr_poly
					(pts
						(arc
							(start -0.3302 -0.4318)
							(mid -0.402042 -0.402042)
							(end -0.4318 -0.3302)
						)
						(arc
							(start -0.4318 0.3302)
							(mid -0.402042 0.402042)
							(end -0.3302 0.4318)
						)
						(arc
							(start 0.3302 0.4318)
							(mid 0.402042 0.402042)
							(end 0.4318 0.3302)
						)
						(arc
							(start 0.4318 -0.3302)
							(mid 0.402042 -0.402042)
							(end 0.3302 -0.4318)
						)
					)
					(width 0)
					(fill yes)
				)
			)
		)
		(pad "2" smd custom
			(at 0 0.762 90)
			(size 0.2159 0.2159)
			(layers "F.Cu" "F.Mask" "F.Paste")
			(net "GND")
			(options
				(clearance outline)
				(anchor circle)
			)
			(primitives
				(gr_poly
					(pts
						(arc
							(start -0.3302 -0.4318)
							(mid -0.402042 -0.402042)
							(end -0.4318 -0.3302)
						)
						(arc
							(start -0.4318 0.3302)
							(mid -0.402042 0.402042)
							(end -0.3302 0.4318)
						)
						(arc
							(start 0.3302 0.4318)
							(mid 0.402042 0.402042)
							(end 0.4318 0.3302)
						)
						(arc
							(start 0.4318 -0.3302)
							(mid 0.402042 -0.402042)
							(end 0.3302 -0.4318)
						)
					)
					(width 0)
					(fill yes)
				)
			)
		)
	)
	(footprint ""
		(layer "F.Cu")
		(at 159.324802 -207.79994)
		(property "Reference" ""
			(at 0 0 0)
			(layer "F.SilkS")
			(hide yes)
			(effects
				(font
					(size 1.27 1.27)
				)
			)
		)
		(property "Value" "*"
			(at -8.398764 -8.057642 0)
			(unlocked yes)
			(layer "F.Fab")
			(hide yes)
			(effects
				(font
					(size 1.016 1.016)
					(thickness 0.1524)
				)
			)
		)
		(duplicate_pad_numbers_are_jumpers no)
		(fp_poly
			(pts
				(arc
					(start 7.3152 0)
					(mid 0 7.3152)
					(end -7.3152 0)
				)
				(arc
					(start -7.3152 -5.9944)
					(mid 0 -13.3096)
					(end 7.3152 -5.9944)
				)
			)
			(stroke
				(width 0)
				(type default)
			)
			(fill no)
			(layer "B.CrtYd")
		)
		(fp_poly
			(pts
				(arc
					(start 7.3152 0)
					(mid 0 7.3152)
					(end -7.3152 0)
				)
				(arc
					(start -7.3152 -5.9944)
					(mid 0 -13.3096)
					(end 7.3152 -5.9944)
				)
			)
			(stroke
				(width 0)
				(type default)
			)
			(fill no)
			(layer "F.CrtYd")
		)
		(fp_poly
			(pts
				(arc
					(start 7.3152 0)
					(mid 0 7.3152)
					(end -7.3152 0)
				)
				(arc
					(start -7.3152 -5.9944)
					(mid 0 -13.3096)
					(end 7.3152 -5.9944)
				)
			)
			(stroke
				(width 0)
				(type default)
			)
			(fill no)
			(layer "B.Fab")
		)
		(fp_poly
			(pts
				(arc
					(start 7.3152 0)
					(mid 0 7.3152)
					(end -7.3152 0)
				)
				(arc
					(start -7.3152 -5.9944)
					(mid 0 -13.3096)
					(end 7.3152 -5.9944)
				)
			)
			(stroke
				(width 0)
				(type default)
			)
			(fill no)
			(layer "F.Fab")
		)
		(pad "1" thru_hole oval
			(at 0 0)
			(size 14.0208 20.0152)
			(drill 0.0254
				(offset 0 -2.9972)
			)
			(layers "*.Cu" "*.Mask")
			(remove_unused_layers no)
			(net "Net_105")
			(clearance -1.002284)
			(thermal_gap 0.1524)
			(padstack
				(mode front_inner_back)
				(layer "Inner"
					(shape custom)
					(size 2.928012 2.928012)
					(options
						(anchor circle)
					)
					(primitives
						(gr_poly
							(pts
								(arc
									(start 4.571746 -2.084324)
									(mid 0.000333 7.430372)
									(end -4.571492 -2.084324)
								)
								(arc
									(start -4.571492 -2.084324)
									(mid -3.570296 -3.611977)
									(end -2.875026 -5.30098)
								)
								(arc
									(start -2.875026 -5.30098)
									(mid 0.000217 -7.43089)
									(end 2.87528 -5.30098)
								)
								(arc
									(start 2.87528 -5.30098)
									(mid 3.570511 -3.611956)
									(end 4.571746 -2.084324)
								)
							)
							(width 0)
							(fill yes)
						)
					)
					(clearance 0.1524)
				)
				(layer "B.Cu"
					(shape oval)
					(size 14.0208 20.0152)
					(offset 0 -2.9972)
					(clearance -1.002284)
				)
			)
		)
		(zone
			(layers "F.Cu" "B.Cu" "In1.Cu" "In2.Cu" "In3.Cu" "In4.Cu" "In5.Cu" "In6.Cu"
				"In7.Cu" "In8.Cu" "In9.Cu" "In10.Cu"
			)
			(hatch none 0.5)
			(connect_pads
				(clearance 0)
			)
			(min_thickness 0.25)
			(keepout
				(tracks not_allowed)
				(vias allowed)
				(pads allowed)
				(copperpour not_allowed)
				(footprints allowed)
			)
			(placement
				(enabled no)
				(sheetname "")
			)
			(fill
				(thermal_gap 0.5)
				(thermal_bridge_width 0.5)
				(island_removal_mode 0)
			)
			(polygon
				(pts
					(arc
						(start 152.314402 -213.79434)
						(mid 159.324802 -220.80474)
						(end 166.335202 -213.79434)
					)
					(arc
						(start 166.335202 -207.79994)
						(mid 159.324802 -200.78954)
						(end 152.314402 -207.79994)
					)
				)
			)
		)
	)
	(footprint ""
		(layer "F.Cu")
		(at 367.338102 -157.585918 180)
		(property "Reference" "R577"
			(at 0 0 180)
			(layer "F.SilkS")
			(hide yes)
			(effects
				(font
					(size 1.27 1.27)
				)
			)
		)
		(property "Value" "0R2J-2-GP"
			(at 0.064008 -3.993896 180)
			(unlocked yes)
			(layer "F.Fab")
			(hide yes)
			(effects
				(font
					(size 1.016 1.016)
					(thickness 0.1524)
				)
			)
		)
		(property "Device Type" "R402H16"
			(at 0.064008 -5.517896 180)
			(unlocked yes)
			(layer "F.Fab")
			(hide yes)
			(effects
				(font
					(size 1.016 1.016)
					(thickness 0.1524)
				)
			)
		)
		(duplicate_pad_numbers_are_jumpers no)
		(fp_line
			(start 0.508 -0.9398)
			(end -0.508 -0.9398)
			(stroke
				(width 0.1524)
				(type default)
			)
			(layer "F.SilkS")
		)
		(fp_line
			(start -0.508 -0.9398)
			(end -0.508 0.9398)
			(stroke
				(width 0.1524)
				(type default)
			)
			(layer "F.SilkS")
		)
		(fp_rect
			(start -0.508 0.9398)
			(end 0.508 -0.9398)
			(stroke
				(width 0)
				(type default)
			)
			(fill no)
			(layer "F.CrtYd")
		)
		(fp_rect
			(start -0.508 0.9398)
			(end 0.508 -0.9398)
			(stroke
				(width 0)
				(type default)
			)
			(fill no)
			(layer "F.Fab")
		)
		(pad "1" smd custom
			(at 0 -0.4445 180)
			(size 0.1397 0.1397)
			(layers "F.Cu" "F.Mask" "F.Paste")
			(net "DRIVE_A_19_PWR")
			(options
				(clearance outline)
				(anchor circle)
			)
			(primitives
				(gr_poly
					(pts
						(arc
							(start -0.1778 -0.2794)
							(mid -0.249642 -0.249642)
							(end -0.2794 -0.1778)
						)
						(arc
							(start -0.2794 0.1778)
							(mid -0.249642 0.249642)
							(end -0.1778 0.2794)
						)
						(arc
							(start 0.1778 0.2794)
							(mid 0.249642 0.249642)
							(end 0.2794 0.1778)
						)
						(arc
							(start 0.2794 -0.1778)
							(mid 0.249642 -0.249642)
							(end 0.1778 -0.2794)
						)
					)
					(width 0)
					(fill yes)
				)
			)
		)
		(pad "2" smd custom
			(at 0 0.4445 180)
			(size 0.1397 0.1397)
			(layers "F.Cu" "F.Mask" "F.Paste")
			(net "SW_PWR_R_HDD19")
			(options
				(clearance outline)
				(anchor circle)
			)
			(primitives
				(gr_poly
					(pts
						(arc
							(start -0.1778 -0.2794)
							(mid -0.249642 -0.249642)
							(end -0.2794 -0.1778)
						)
						(arc
							(start -0.2794 0.1778)
							(mid -0.249642 0.249642)
							(end -0.1778 0.2794)
						)
						(arc
							(start 0.1778 0.2794)
							(mid 0.249642 0.249642)
							(end 0.2794 0.1778)
						)
						(arc
							(start 0.2794 -0.1778)
							(mid 0.249642 -0.249642)
							(end 0.1778 -0.2794)
						)
					)
					(width 0)
					(fill yes)
				)
			)
		)
	)
	(footprint ""
		(layer "F.Cu")
		(at 248.608342 -383.085848 90)
		(property "Reference" "Q225"
			(at 0 0 90)
			(layer "F.SilkS")
			(hide yes)
			(effects
				(font
					(size 1.27 1.27)
				)
			)
		)
		(property "Value" "MMBT3904-3-GP"
			(at 0.10287 -10.29843 90)
			(unlocked yes)
			(layer "F.Fab")
			(hide yes)
			(effects
				(font
					(size 1.016 1.016)
					(thickness 0.1524)
				)
			)
		)
		(property "Device Type" "SOT23CBE2D4H44"
			(at 0.10287 -12.20343 90)
			(unlocked yes)
			(layer "F.Fab")
			(hide yes)
			(effects
				(font
					(size 1.016 1.016)
					(thickness 0.1524)
				)
			)
		)
		(duplicate_pad_numbers_are_jumpers no)
		(fp_line
			(start 1.651 -1.778)
			(end -1.651 -1.778)
			(stroke
				(width 0.1524)
				(type default)
			)
			(layer "F.SilkS")
		)
		(fp_line
			(start -1.651 -1.778)
			(end -1.651 1.778)
			(stroke
				(width 0.1524)
				(type default)
			)
			(layer "F.SilkS")
		)
		(fp_line
			(start 1.651 1.778)
			(end 1.651 -1.778)
			(stroke
				(width 0.1524)
				(type default)
			)
			(layer "F.SilkS")
		)
		(fp_line
			(start -1.651 1.778)
			(end 1.651 1.778)
			(stroke
				(width 0.1524)
				(type default)
			)
			(layer "F.SilkS")
		)
		(fp_poly
			(pts
				(xy -1.778 1.8796) (xy -1.778 -1.8796) (xy 1.778 -1.8796) (xy 1.778 1.8796)
			)
			(stroke
				(width 0)
				(type default)
			)
			(fill no)
			(layer "F.CrtYd")
		)
		(fp_poly
			(pts
				(xy -1.778 1.8796) (xy -1.778 -1.8796) (xy 1.778 -1.8796) (xy 1.778 1.8796)
			)
			(stroke
				(width 0)
				(type default)
			)
			(fill no)
			(layer "F.Fab")
		)
		(pad "B" smd custom
			(at -0.98425 0.9525 90)
			(size 0.1905 0.1905)
			(layers "F.Cu" "F.Mask" "F.Paste")
			(net "MB3_TEMP_B")
			(options
				(clearance outline)
				(anchor circle)
			)
			(primitives
				(gr_poly
					(pts
						(arc
							(start -0.1778 0.5715)
							(mid -0.321484 0.511984)
							(end -0.381 0.3683)
						)
						(arc
							(start -0.381 -0.3683)
							(mid -0.321484 -0.511984)
							(end -0.1778 -0.5715)
						)
						(arc
							(start 0.1778 -0.5715)
							(mid 0.321484 -0.511984)
							(end 0.381 -0.3683)
						)
						(arc
							(start 0.381 0.3683)
							(mid 0.321484 0.511984)
							(end 0.1778 0.5715)
						)
					)
					(width 0)
					(fill yes)
				)
			)
		)
		(pad "C" smd custom
			(at 0 -0.9525 90)
			(size 0.1905 0.1905)
			(layers "F.Cu" "F.Mask" "F.Paste")
			(net "MB3_TEMP_B")
			(options
				(clearance outline)
				(anchor circle)
			)
			(primitives
				(gr_poly
					(pts
						(arc
							(start -0.1778 0.5715)
							(mid -0.321484 0.511984)
							(end -0.381 0.3683)
						)
						(arc
							(start -0.381 -0.3683)
							(mid -0.321484 -0.511984)
							(end -0.1778 -0.5715)
						)
						(arc
							(start 0.1778 -0.5715)
							(mid 0.321484 -0.511984)
							(end 0.381 -0.3683)
						)
						(arc
							(start 0.381 0.3683)
							(mid 0.321484 0.511984)
							(end 0.1778 0.5715)
						)
					)
					(width 0)
					(fill yes)
				)
			)
		)
		(pad "E" smd custom
			(at 0.98425 0.9525 90)
			(size 0.1905 0.1905)
			(layers "F.Cu" "F.Mask" "F.Paste")
			(net "MB3_TEMP_E")
			(options
				(clearance outline)
				(anchor circle)
			)
			(primitives
				(gr_poly
					(pts
						(arc
							(start -0.1778 0.5715)
							(mid -0.321484 0.511984)
							(end -0.381 0.3683)
						)
						(arc
							(start -0.381 -0.3683)
							(mid -0.321484 -0.511984)
							(end -0.1778 -0.5715)
						)
						(arc
							(start 0.1778 -0.5715)
							(mid 0.321484 -0.511984)
							(end 0.381 -0.3683)
						)
						(arc
							(start 0.381 0.3683)
							(mid 0.321484 0.511984)
							(end 0.1778 0.5715)
						)
					)
					(width 0)
					(fill yes)
				)
			)
		)
	)
	(footprint ""
		(layer "F.Cu")
		(at 304.546 -74.676)
		(property "Reference" "R449"
			(at 0 0 0)
			(layer "F.SilkS")
			(hide yes)
			(effects
				(font
					(size 1.27 1.27)
				)
			)
		)
		(property "Value" "0R2J-2-GP"
			(at 0.064008 -3.993896 0)
			(unlocked yes)
			(layer "F.Fab")
			(hide yes)
			(effects
				(font
					(size 1.016 1.016)
					(thickness 0.1524)
				)
			)
		)
		(property "Device Type" "R402H16"
			(at 0.064008 -5.517896 0)
			(unlocked yes)
			(layer "F.Fab")
			(hide yes)
			(effects
				(font
					(size 1.016 1.016)
					(thickness 0.1524)
				)
			)
		)
		(duplicate_pad_numbers_are_jumpers no)
		(fp_line
			(start -0.508 -0.9398)
			(end -0.508 0.9398)
			(stroke
				(width 0.1524)
				(type default)
			)
			(layer "F.SilkS")
		)
		(fp_line
			(start 0.508 -0.9398)
			(end -0.508 -0.9398)
			(stroke
				(width 0.1524)
				(type default)
			)
			(layer "F.SilkS")
		)
		(fp_rect
			(start -0.508 0.9398)
			(end 0.508 -0.9398)
			(stroke
				(width 0)
				(type default)
			)
			(fill no)
			(layer "F.CrtYd")
		)
		(fp_rect
			(start -0.508 0.9398)
			(end 0.508 -0.9398)
			(stroke
				(width 0)
				(type default)
			)
			(fill no)
			(layer "F.Fab")
		)
		(pad "1" smd custom
			(at 0 -0.4445)
			(size 0.1397 0.1397)
			(layers "F.Cu" "F.Mask" "F.Paste")
			(net "COMP_B_PGOOD")
			(options
				(clearance outline)
				(anchor circle)
			)
			(primitives
				(gr_poly
					(pts
						(arc
							(start -0.1778 -0.2794)
							(mid -0.249642 -0.249642)
							(end -0.2794 -0.1778)
						)
						(arc
							(start -0.2794 0.1778)
							(mid -0.249642 0.249642)
							(end -0.1778 0.2794)
						)
						(arc
							(start 0.1778 0.2794)
							(mid 0.249642 0.249642)
							(end 0.2794 0.1778)
						)
						(arc
							(start 0.2794 -0.1778)
							(mid 0.249642 -0.249642)
							(end 0.1778 -0.2794)
						)
					)
					(width 0)
					(fill yes)
				)
			)
		)
		(pad "2" smd custom
			(at 0 0.4445)
			(size 0.1397 0.1397)
			(layers "F.Cu" "F.Mask" "F.Paste")
			(net "TXS0102_B_OE")
			(options
				(clearance outline)
				(anchor circle)
			)
			(primitives
				(gr_poly
					(pts
						(arc
							(start -0.1778 -0.2794)
							(mid -0.249642 -0.249642)
							(end -0.2794 -0.1778)
						)
						(arc
							(start -0.2794 0.1778)
							(mid -0.249642 0.249642)
							(end -0.1778 0.2794)
						)
						(arc
							(start 0.1778 0.2794)
							(mid 0.249642 0.249642)
							(end 0.2794 0.1778)
						)
						(arc
							(start 0.2794 -0.1778)
							(mid 0.249642 -0.249642)
							(end 0.1778 -0.2794)
						)
					)
					(width 0)
					(fill yes)
				)
			)
		)
	)
)
